(kicad_pcb
	(version 20260206)
	(generator "pcbnew")
	(generator_version "10.0")
	(general
		(thickness 1.6)
		(legacy_teardrops no)
	)
	(paper "A4")
	(title_block
		(title "01162023_DA0F0TEBIF0_F0T_Expander_BD_F_brd_V02_OCP.brd")
		(comment 1 "Grand Teton / footprints 275-280 of 9728")
	)
	(layers
		(0 "F.Cu" signal "TOP")
		(4 "In1.Cu" signal "GND")
		(6 "In2.Cu" signal "VCC")
		(8 "In3.Cu" signal "VCC1")
		(10 "In4.Cu" signal "GND1")
		(12 "In5.Cu" signal "IN1")
		(14 "In6.Cu" signal "GND2")
		(16 "In7.Cu" signal "IN2")
		(18 "In8.Cu" signal "GND3")
		(20 "In9.Cu" signal "IN3")
		(22 "In10.Cu" signal "GND4")
		(24 "In11.Cu" signal "IN4")
		(26 "In12.Cu" signal "GND5")
		(28 "In13.Cu" signal "IN5")
		(30 "In14.Cu" signal "GND6")
		(32 "In15.Cu" signal "IN6")
		(34 "In16.Cu" signal "GND7")
		(2 "B.Cu" signal "BOTTOM")
		(9 "F.Adhes" user "F.Adhesive")
		(11 "B.Adhes" user "B.Adhesive")
		(13 "F.Paste" user "Package Geometry/Pastemask Top")
		(15 "B.Paste" user "Package Geometry/Pastemask Bottom")
		(5 "F.SilkS" user "Ref Des/Silkscreen Top")
		(7 "B.SilkS" user "Ref Des/Silkscreen Bottom")
		(1 "F.Mask" user "Board Geometry/Soldermask Top")
		(3 "B.Mask" user "Board Geometry/Soldermask Bottom")
		(17 "Dwgs.User" user "User.Drawings")
		(19 "Cmts.User" user "User.Comments")
		(21 "Eco1.User" user "User.Eco1")
		(23 "Eco2.User" user "User.Eco2")
		(25 "Edge.Cuts" user "Board Geometry/Outline")
		(27 "Margin" user)
		(31 "F.CrtYd" user "Package Geometry/Place Bound Top")
		(29 "B.CrtYd" user "Package Geometry/Place Bound Bottom")
		(35 "F.Fab" user "Ref Des/Assembly Top")
		(33 "B.Fab" user "Ref Des/Assembly Bottom")
	)
	(footprint ""
		(layer "F.Cu")
		(at 231.764586 -112.205516 180)
		(property "Reference" "PC599"
			(at 0 0 180)
			(layer "F.SilkS")
			(hide yes)
			(effects
				(font
					(size 1.27 1.27)
				)
			)
		)
		(property "Value" ""
			(at 0 0 180)
			(layer "F.Fab")
			(effects
				(font
					(size 1.27 1.27)
				)
			)
		)
		(duplicate_pad_numbers_are_jumpers no)
		(fp_line
			(start 0.7874 0.4064)
			(end -0.7874 0.4064)
			(stroke
				(width 0.1524)
				(type default)
			)
			(layer "F.SilkS")
		)
		(fp_line
			(start 0.7874 -0.4064)
			(end 0.7874 0.4064)
			(stroke
				(width 0.1524)
				(type default)
			)
			(layer "F.SilkS")
		)
		(fp_line
			(start -0.7874 0.4064)
			(end -0.7874 -0.4064)
			(stroke
				(width 0.1524)
				(type default)
			)
			(layer "F.SilkS")
		)
		(fp_line
			(start -0.7874 -0.4064)
			(end 0.7874 -0.4064)
			(stroke
				(width 0.1524)
				(type default)
			)
			(layer "F.SilkS")
		)
		(fp_line
			(start 0.67945 0.3048)
			(end 0.120396 0.3048)
			(stroke
				(width 0.1)
				(type default)
			)
			(layer "F.Fab")
		)
		(fp_line
			(start 0.67945 -0.3048)
			(end 0.67945 0.3048)
			(stroke
				(width 0.1)
				(type default)
			)
			(layer "F.Fab")
		)
		(fp_line
			(start 0.12065 -0.2794)
			(end 0.12065 -0.3048)
			(stroke
				(width 0.1)
				(type default)
			)
			(layer "F.Fab")
		)
		(fp_line
			(start 0.12065 -0.3048)
			(end 0.67945 -0.3048)
			(stroke
				(width 0.1)
				(type default)
			)
			(layer "F.Fab")
		)
		(fp_line
			(start 0.120396 0.3048)
			(end 0.120396 0.2794)
			(stroke
				(width 0.1)
				(type default)
			)
			(layer "F.Fab")
		)
		(fp_line
			(start 0.120396 0.2794)
			(end -0.12065 0.2794)
			(stroke
				(width 0.1)
				(type default)
			)
			(layer "F.Fab")
		)
		(fp_line
			(start -0.12065 0.3048)
			(end -0.67945 0.3048)
			(stroke
				(width 0.1)
				(type default)
			)
			(layer "F.Fab")
		)
		(fp_line
			(start -0.12065 0.2794)
			(end -0.12065 0.3048)
			(stroke
				(width 0.1)
				(type default)
			)
			(layer "F.Fab")
		)
		(fp_line
			(start -0.12065 -0.2794)
			(end 0.12065 -0.2794)
			(stroke
				(width 0.1)
				(type default)
			)
			(layer "F.Fab")
		)
		(fp_line
			(start -0.12065 -0.305054)
			(end -0.12065 -0.2794)
			(stroke
				(width 0.1)
				(type default)
			)
			(layer "F.Fab")
		)
		(fp_line
			(start -0.67945 0.3048)
			(end -0.67945 -0.305054)
			(stroke
				(width 0.1)
				(type default)
			)
			(layer "F.Fab")
		)
		(fp_line
			(start -0.67945 -0.305054)
			(end -0.12065 -0.305054)
			(stroke
				(width 0.1)
				(type default)
			)
			(layer "F.Fab")
		)
		(pad "1" smd circle
			(at -0.40005 0 180)
			(size 0 0)
			(layers "F.Cu" "F.Mask" "F.Paste")
			(net "P12V_AUX")
		)
		(pad "2" smd circle
			(at 0.40005 0 180)
			(size 0 0)
			(layers "F.Cu" "F.Mask" "F.Paste")
			(net "GND")
		)
	)
	(footprint ""
		(layer "F.Cu")
		(at 334.095852 -113.547398 90)
		(property "Reference" "PR7025"
			(at 0 0 90)
			(layer "F.SilkS")
			(hide yes)
			(effects
				(font
					(size 1.27 1.27)
				)
			)
		)
		(property "Value" ""
			(at 0 0 90)
			(layer "F.Fab")
			(effects
				(font
					(size 1.27 1.27)
				)
			)
		)
		(duplicate_pad_numbers_are_jumpers no)
		(fp_line
			(start 0.7874 -0.4064)
			(end 0.7874 0.4064)
			(stroke
				(width 0.1524)
				(type default)
			)
			(layer "F.SilkS")
		)
		(fp_line
			(start -0.7874 -0.4064)
			(end 0.7874 -0.4064)
			(stroke
				(width 0.1524)
				(type default)
			)
			(layer "F.SilkS")
		)
		(fp_line
			(start 0.7874 0.4064)
			(end -0.7874 0.4064)
			(stroke
				(width 0.1524)
				(type default)
			)
			(layer "F.SilkS")
		)
		(fp_line
			(start -0.7874 0.4064)
			(end -0.7874 -0.4064)
			(stroke
				(width 0.1524)
				(type default)
			)
			(layer "F.SilkS")
		)
		(fp_line
			(start -0.12065 -0.305054)
			(end -0.12065 -0.2794)
			(stroke
				(width 0.1)
				(type default)
			)
			(layer "F.Fab")
		)
		(fp_line
			(start -0.67945 -0.305054)
			(end -0.12065 -0.305054)
			(stroke
				(width 0.1)
				(type default)
			)
			(layer "F.Fab")
		)
		(fp_line
			(start 0.67945 -0.3048)
			(end 0.67945 0.3048)
			(stroke
				(width 0.1)
				(type default)
			)
			(layer "F.Fab")
		)
		(fp_line
			(start 0.12065 -0.3048)
			(end 0.67945 -0.3048)
			(stroke
				(width 0.1)
				(type default)
			)
			(layer "F.Fab")
		)
		(fp_line
			(start 0.12065 -0.2794)
			(end 0.12065 -0.3048)
			(stroke
				(width 0.1)
				(type default)
			)
			(layer "F.Fab")
		)
		(fp_line
			(start -0.12065 -0.2794)
			(end 0.12065 -0.2794)
			(stroke
				(width 0.1)
				(type default)
			)
			(layer "F.Fab")
		)
		(fp_line
			(start 0.120396 0.2794)
			(end -0.12065 0.2794)
			(stroke
				(width 0.1)
				(type default)
			)
			(layer "F.Fab")
		)
		(fp_line
			(start -0.12065 0.2794)
			(end -0.12065 0.3048)
			(stroke
				(width 0.1)
				(type default)
			)
			(layer "F.Fab")
		)
		(fp_line
			(start 0.67945 0.3048)
			(end 0.120396 0.3048)
			(stroke
				(width 0.1)
				(type default)
			)
			(layer "F.Fab")
		)
		(fp_line
			(start 0.120396 0.3048)
			(end 0.120396 0.2794)
			(stroke
				(width 0.1)
				(type default)
			)
			(layer "F.Fab")
		)
		(fp_line
			(start -0.12065 0.3048)
			(end -0.67945 0.3048)
			(stroke
				(width 0.1)
				(type default)
			)
			(layer "F.Fab")
		)
		(fp_line
			(start -0.67945 0.3048)
			(end -0.67945 -0.305054)
			(stroke
				(width 0.1)
				(type default)
			)
			(layer "F.Fab")
		)
		(pad "1" smd circle
			(at -0.40005 0 90)
			(size 0 0)
			(layers "F.Cu" "F.Mask" "F.Paste")
			(net "P12V_NIC5_R")
		)
		(pad "2" smd circle
			(at 0.40005 0 90)
			(size 0 0)
			(layers "F.Cu" "F.Mask" "F.Paste")
			(net "P12V_NIC5_CO_AVIN_PD")
		)
	)
	(footprint ""
		(layer "F.Cu")
		(at 193.83883 -402.663152 -90)
		(property "Reference" "C2844"
			(at 0 0 270)
			(layer "F.SilkS")
			(hide yes)
			(effects
				(font
					(size 1.27 1.27)
				)
			)
		)
		(property "Value" ""
			(at 0 0 270)
			(layer "F.Fab")
			(effects
				(font
					(size 1.27 1.27)
				)
			)
		)
		(duplicate_pad_numbers_are_jumpers no)
		(fp_line
			(start -0.7874 0.4064)
			(end -0.7874 -0.4064)
			(stroke
				(width 0.1524)
				(type default)
			)
			(layer "F.SilkS")
		)
		(fp_line
			(start 0.7874 0.4064)
			(end -0.7874 0.4064)
			(stroke
				(width 0.1524)
				(type default)
			)
			(layer "F.SilkS")
		)
		(fp_line
			(start -0.7874 -0.4064)
			(end 0.7874 -0.4064)
			(stroke
				(width 0.1524)
				(type default)
			)
			(layer "F.SilkS")
		)
		(fp_line
			(start 0.7874 -0.4064)
			(end 0.7874 0.4064)
			(stroke
				(width 0.1524)
				(type default)
			)
			(layer "F.SilkS")
		)
		(fp_line
			(start -0.67945 0.3048)
			(end -0.67945 -0.305054)
			(stroke
				(width 0.1)
				(type default)
			)
			(layer "F.Fab")
		)
		(fp_line
			(start -0.12065 0.3048)
			(end -0.67945 0.3048)
			(stroke
				(width 0.1)
				(type default)
			)
			(layer "F.Fab")
		)
		(fp_line
			(start 0.120396 0.3048)
			(end 0.120396 0.2794)
			(stroke
				(width 0.1)
				(type default)
			)
			(layer "F.Fab")
		)
		(fp_line
			(start 0.67945 0.3048)
			(end 0.120396 0.3048)
			(stroke
				(width 0.1)
				(type default)
			)
			(layer "F.Fab")
		)
		(fp_line
			(start -0.12065 0.2794)
			(end -0.12065 0.3048)
			(stroke
				(width 0.1)
				(type default)
			)
			(layer "F.Fab")
		)
		(fp_line
			(start 0.120396 0.2794)
			(end -0.12065 0.2794)
			(stroke
				(width 0.1)
				(type default)
			)
			(layer "F.Fab")
		)
		(fp_line
			(start -0.12065 -0.2794)
			(end 0.12065 -0.2794)
			(stroke
				(width 0.1)
				(type default)
			)
			(layer "F.Fab")
		)
		(fp_line
			(start 0.12065 -0.2794)
			(end 0.12065 -0.3048)
			(stroke
				(width 0.1)
				(type default)
			)
			(layer "F.Fab")
		)
		(fp_line
			(start 0.12065 -0.3048)
			(end 0.67945 -0.3048)
			(stroke
				(width 0.1)
				(type default)
			)
			(layer "F.Fab")
		)
		(fp_line
			(start 0.67945 -0.3048)
			(end 0.67945 0.3048)
			(stroke
				(width 0.1)
				(type default)
			)
			(layer "F.Fab")
		)
		(fp_line
			(start -0.67945 -0.305054)
			(end -0.12065 -0.305054)
			(stroke
				(width 0.1)
				(type default)
			)
			(layer "F.Fab")
		)
		(fp_line
			(start -0.12065 -0.305054)
			(end -0.12065 -0.2794)
			(stroke
				(width 0.1)
				(type default)
			)
			(layer "F.Fab")
		)
		(pad "1" smd circle
			(at -0.40005 0 270)
			(size 0 0)
			(layers "F.Cu" "F.Mask" "F.Paste")
			(net "FM_UV_LT6700_VS")
		)
		(pad "2" smd circle
			(at 0.40005 0 270)
			(size 0 0)
			(layers "F.Cu" "F.Mask" "F.Paste")
			(net "GND")
		)
	)
	(footprint ""
		(layer "F.Cu")
		(at 147.854416 -48.21809)
		(property "Reference" "PD63"
			(at -3.328416 2.19456 0)
			(unlocked yes)
			(layer "F.SilkS")
			(effects
				(font
					(size 0.7874 0.5842)
					(thickness 0.1524)
				)
				(justify left)
			)
		)
		(property "Value" ""
			(at 0 0 0)
			(layer "F.Fab")
			(effects
				(font
					(size 1.27 1.27)
				)
			)
		)
		(duplicate_pad_numbers_are_jumpers no)
		(fp_line
			(start -3.400044 -1.459992)
			(end 4.107942 -1.459992)
			(stroke
				(width 0.1524)
				(type default)
			)
			(layer "F.SilkS")
		)
		(fp_line
			(start -3.400044 1.459992)
			(end -3.400044 -1.459992)
			(stroke
				(width 0.1524)
				(type default)
			)
			(layer "F.SilkS")
		)
		(fp_line
			(start 4.107942 -1.459992)
			(end 4.107942 1.459992)
			(stroke
				(width 0.1524)
				(type default)
			)
			(layer "F.SilkS")
		)
		(fp_line
			(start 4.107942 1.459992)
			(end -3.400044 1.459992)
			(stroke
				(width 0.1524)
				(type default)
			)
			(layer "F.SilkS")
		)
		(fp_poly
			(pts
				(xy 4.107942 -1.459992) (xy 4.107942 1.459992) (xy 3.308096 1.459992) (xy 3.308096 -1.459992)
			)
			(stroke
				(width 0)
				(type default)
			)
			(fill yes)
			(layer "F.SilkS")
		)
		(fp_line
			(start -2.29997 -1.459992)
			(end 2.29997 -1.459992)
			(stroke
				(width 0.1)
				(type default)
			)
			(layer "F.Fab")
		)
		(fp_line
			(start -2.29997 1.459992)
			(end -2.29997 -1.459992)
			(stroke
				(width 0.1)
				(type default)
			)
			(layer "F.Fab")
		)
		(fp_line
			(start 2.29997 -1.459992)
			(end 2.29997 1.459992)
			(stroke
				(width 0.1)
				(type default)
			)
			(layer "F.Fab")
		)
		(fp_line
			(start 2.29997 1.459992)
			(end -2.29997 1.459992)
			(stroke
				(width 0.1)
				(type default)
			)
			(layer "F.Fab")
		)
		(fp_text user "+"
			(at -4.7752 -0.12065 0)
			(unlocked yes)
			(layer "F.SilkS")
			(effects
				(font
					(size 1.905 1.4224)
					(thickness 0.1524)
				)
				(justify left)
			)
		)
		(fp_text user "-"
			(at 5.4102 0.29845 180)
			(unlocked yes)
			(layer "F.SilkS")
			(effects
				(font
					(size 1.905 1.4224)
					(thickness 0.1524)
				)
				(justify left)
			)
		)
		(fp_text user "+"
			(at -4.7752 -0.12065 0)
			(unlocked yes)
			(layer "F.Fab")
			(effects
				(font
					(size 1.905 1.4224)
					(thickness 0.1524)
				)
				(justify left)
			)
		)
		(fp_text user "-"
			(at 5.4102 0.29845 180)
			(unlocked yes)
			(layer "F.Fab")
			(effects
				(font
					(size 1.905 1.4224)
					(thickness 0.1524)
				)
				(justify left)
			)
		)
		(pad "A" smd rect
			(at -1.999996 0 90)
			(size 1.7018 2.5146)
			(layers "F.Cu" "F.Mask" "F.Paste")
			(net "GND")
		)
		(pad "C" smd rect
			(at 1.999996 0 90)
			(size 1.7018 2.5146)
			(layers "F.Cu" "F.Mask" "F.Paste")
			(net "P3V3_SSD5")
		)
	)
	(footprint ""
		(layer "F.Cu")
		(at 252.99543 -92.096336 -90)
		(property "Reference" "R1067"
			(at 0 0 270)
			(layer "F.SilkS")
			(hide yes)
			(effects
				(font
					(size 1.27 1.27)
				)
			)
		)
		(property "Value" ""
			(at 0 0 270)
			(layer "F.Fab")
			(effects
				(font
					(size 1.27 1.27)
				)
			)
		)
		(duplicate_pad_numbers_are_jumpers no)
		(fp_line
			(start -0.7874 0.4064)
			(end -0.7874 -0.4064)
			(stroke
				(width 0.1524)
				(type default)
			)
			(layer "F.SilkS")
		)
		(fp_line
			(start 0.7874 0.4064)
			(end -0.7874 0.4064)
			(stroke
				(width 0.1524)
				(type default)
			)
			(layer "F.SilkS")
		)
		(fp_line
			(start -0.7874 -0.4064)
			(end 0.7874 -0.4064)
			(stroke
				(width 0.1524)
				(type default)
			)
			(layer "F.SilkS")
		)
		(fp_line
			(start 0.7874 -0.4064)
			(end 0.7874 0.4064)
			(stroke
				(width 0.1524)
				(type default)
			)
			(layer "F.SilkS")
		)
		(fp_line
			(start -0.67945 0.3048)
			(end -0.67945 -0.305054)
			(stroke
				(width 0.1)
				(type default)
			)
			(layer "F.Fab")
		)
		(fp_line
			(start -0.12065 0.3048)
			(end -0.67945 0.3048)
			(stroke
				(width 0.1)
				(type default)
			)
			(layer "F.Fab")
		)
		(fp_line
			(start 0.120396 0.3048)
			(end 0.120396 0.2794)
			(stroke
				(width 0.1)
				(type default)
			)
			(layer "F.Fab")
		)
		(fp_line
			(start 0.67945 0.3048)
			(end 0.120396 0.3048)
			(stroke
				(width 0.1)
				(type default)
			)
			(layer "F.Fab")
		)
		(fp_line
			(start -0.12065 0.2794)
			(end -0.12065 0.3048)
			(stroke
				(width 0.1)
				(type default)
			)
			(layer "F.Fab")
		)
		(fp_line
			(start 0.120396 0.2794)
			(end -0.12065 0.2794)
			(stroke
				(width 0.1)
				(type default)
			)
			(layer "F.Fab")
		)
		(fp_line
			(start -0.12065 -0.2794)
			(end 0.12065 -0.2794)
			(stroke
				(width 0.1)
				(type default)
			)
			(layer "F.Fab")
		)
		(fp_line
			(start 0.12065 -0.2794)
			(end 0.12065 -0.3048)
			(stroke
				(width 0.1)
				(type default)
			)
			(layer "F.Fab")
		)
		(fp_line
			(start 0.12065 -0.3048)
			(end 0.67945 -0.3048)
			(stroke
				(width 0.1)
				(type default)
			)
			(layer "F.Fab")
		)
		(fp_line
			(start 0.67945 -0.3048)
			(end 0.67945 0.3048)
			(stroke
				(width 0.1)
				(type default)
			)
			(layer "F.Fab")
		)
		(fp_line
			(start -0.67945 -0.305054)
			(end -0.12065 -0.305054)
			(stroke
				(width 0.1)
				(type default)
			)
			(layer "F.Fab")
		)
		(fp_line
			(start -0.12065 -0.305054)
			(end -0.12065 -0.2794)
			(stroke
				(width 0.1)
				(type default)
			)
			(layer "F.Fab")
		)
		(pad "1" smd circle
			(at -0.40005 0 270)
			(size 0 0)
			(layers "F.Cu" "F.Mask" "F.Paste")
			(net "GND")
		)
		(pad "2" smd circle
			(at 0.40005 0 270)
			(size 0 0)
			(layers "F.Cu" "F.Mask" "F.Paste")
			(net "PD_CK440_SBI_DATA_IN")
		)
	)
	(footprint ""
		(layer "F.Cu")
		(at 138.985244 -99.243642)
		(property "Reference" "R1613"
			(at 0 0 0)
			(layer "F.SilkS")
			(hide yes)
			(effects
				(font
					(size 1.27 1.27)
				)
			)
		)
		(property "Value" ""
			(at 0 0 0)
			(layer "F.Fab")
			(effects
				(font
					(size 1.27 1.27)
				)
			)
		)
		(duplicate_pad_numbers_are_jumpers no)
		(fp_line
			(start -0.7874 -0.4064)
			(end 0.7874 -0.4064)
			(stroke
				(width 0.1524)
				(type default)
			)
			(layer "F.SilkS")
		)
		(fp_line
			(start -0.7874 0.4064)
			(end -0.7874 -0.4064)
			(stroke
				(width 0.1524)
				(type default)
			)
			(layer "F.SilkS")
		)
		(fp_line
			(start 0.7874 -0.4064)
			(end 0.7874 0.4064)
			(stroke
				(width 0.1524)
				(type default)
			)
			(layer "F.SilkS")
		)
		(fp_line
			(start 0.7874 0.4064)
			(end -0.7874 0.4064)
			(stroke
				(width 0.1524)
				(type default)
			)
			(layer "F.SilkS")
		)
		(fp_line
			(start -0.67945 -0.305054)
			(end -0.12065 -0.305054)
			(stroke
				(width 0.1)
				(type default)
			)
			(layer "F.Fab")
		)
		(fp_line
			(start -0.67945 0.3048)
			(end -0.67945 -0.305054)
			(stroke
				(width 0.1)
				(type default)
			)
			(layer "F.Fab")
		)
		(fp_line
			(start -0.12065 -0.305054)
			(end -0.12065 -0.2794)
			(stroke
				(width 0.1)
				(type default)
			)
			(layer "F.Fab")
		)
		(fp_line
			(start -0.12065 -0.2794)
			(end 0.12065 -0.2794)
			(stroke
				(width 0.1)
				(type default)
			)
			(layer "F.Fab")
		)
		(fp_line
			(start -0.12065 0.2794)
			(end -0.12065 0.3048)
			(stroke
				(width 0.1)
				(type default)
			)
			(layer "F.Fab")
		)
		(fp_line
			(start -0.12065 0.3048)
			(end -0.67945 0.3048)
			(stroke
				(width 0.1)
				(type default)
			)
			(layer "F.Fab")
		)
		(fp_line
			(start 0.120396 0.2794)
			(end -0.12065 0.2794)
			(stroke
				(width 0.1)
				(type default)
			)
			(layer "F.Fab")
		)
		(fp_line
			(start 0.120396 0.3048)
			(end 0.120396 0.2794)
			(stroke
				(width 0.1)
				(type default)
			)
			(layer "F.Fab")
		)
		(fp_line
			(start 0.12065 -0.3048)
			(end 0.67945 -0.3048)
			(stroke
				(width 0.1)
				(type default)
			)
			(layer "F.Fab")
		)
		(fp_line
			(start 0.12065 -0.2794)
			(end 0.12065 -0.3048)
			(stroke
				(width 0.1)
				(type default)
			)
			(layer "F.Fab")
		)
		(fp_line
			(start 0.67945 -0.3048)
			(end 0.67945 0.3048)
			(stroke
				(width 0.1)
				(type default)
			)
			(layer "F.Fab")
		)
		(fp_line
			(start 0.67945 0.3048)
			(end 0.120396 0.3048)
			(stroke
				(width 0.1)
				(type default)
			)
			(layer "F.Fab")
		)
		(pad "1" smd circle
			(at -0.40005 0)
			(size 0 0)
			(layers "F.Cu" "F.Mask" "F.Paste")
			(net "SMB_BIC_I2C9_SSD_MUX_R_SDA")
		)
		(pad "2" smd circle
			(at 0.40005 0)
			(size 0 0)
			(layers "F.Cu" "F.Mask" "F.Paste")
			(net "SMB_BIC_I2C9_SSD_MUX1_SDA")
		)
	)
)
